(kicad_pcb
	(version 20260206)
	(generator "pcbnew")
	(generator_version "10.0")
	(general
		(thickness 1.6)
		(legacy_teardrops no)
	)
	(paper "A4")
	(title_block
		(title "01162023_DA0F0TEBIF0_F0T_Expander_BD_F_brd_V02_OCP.brd")
		(comment 1 "Grand Teton / footprints 7201-7207 of 9728")
	)
	(layers
		(0 "F.Cu" signal "TOP")
		(4 "In1.Cu" signal "GND")
		(6 "In2.Cu" signal "VCC")
		(8 "In3.Cu" signal "VCC1")
		(10 "In4.Cu" signal "GND1")
		(12 "In5.Cu" signal "IN1")
		(14 "In6.Cu" signal "GND2")
		(16 "In7.Cu" signal "IN2")
		(18 "In8.Cu" signal "GND3")
		(20 "In9.Cu" signal "IN3")
		(22 "In10.Cu" signal "GND4")
		(24 "In11.Cu" signal "IN4")
		(26 "In12.Cu" signal "GND5")
		(28 "In13.Cu" signal "IN5")
		(30 "In14.Cu" signal "GND6")
		(32 "In15.Cu" signal "IN6")
		(34 "In16.Cu" signal "GND7")
		(2 "B.Cu" signal "BOTTOM")
		(9 "F.Adhes" user "F.Adhesive")
		(11 "B.Adhes" user "B.Adhesive")
		(13 "F.Paste" user "Package Geometry/Pastemask Top")
		(15 "B.Paste" user "Package Geometry/Pastemask Bottom")
		(5 "F.SilkS" user "Ref Des/Silkscreen Top")
		(7 "B.SilkS" user "Ref Des/Silkscreen Bottom")
		(1 "F.Mask" user "Board Geometry/Soldermask Top")
		(3 "B.Mask" user "Board Geometry/Soldermask Bottom")
		(17 "Dwgs.User" user "User.Drawings")
		(19 "Cmts.User" user "User.Comments")
		(21 "Eco1.User" user "User.Eco1")
		(23 "Eco2.User" user "User.Eco2")
		(25 "Edge.Cuts" user "Board Geometry/Outline")
		(27 "Margin" user)
		(31 "F.CrtYd" user "Package Geometry/Place Bound Top")
		(29 "B.CrtYd" user "Package Geometry/Place Bound Bottom")
		(35 "F.Fab" user "Ref Des/Assembly Top")
		(33 "B.Fab" user "Ref Des/Assembly Bottom")
	)
	(footprint ""
		(layer "B.Cu")
		(at 458.540866 -272.91792 180)
		(property "Reference" "C4403"
			(at 0 0 0)
			(layer "B.SilkS")
			(hide yes)
			(effects
				(font
					(size 1.27 1.27)
				)
				(justify mirror)
			)
		)
		(property "Value" ""
			(at 0 0 0)
			(layer "B.Fab")
			(effects
				(font
					(size 1.27 1.27)
				)
				(justify mirror)
			)
		)
		(duplicate_pad_numbers_are_jumpers no)
		(fp_line
			(start 1.2954 0.5842)
			(end 1.2954 -0.5842)
			(stroke
				(width 0.1524)
				(type default)
			)
			(layer "B.SilkS")
		)
		(fp_line
			(start 1.2954 -0.5842)
			(end -1.2954 -0.5842)
			(stroke
				(width 0.1524)
				(type default)
			)
			(layer "B.SilkS")
		)
		(fp_line
			(start -1.2954 0.5842)
			(end 1.2954 0.5842)
			(stroke
				(width 0.1524)
				(type default)
			)
			(layer "B.SilkS")
		)
		(fp_line
			(start -1.2954 -0.5842)
			(end -1.2954 0.5842)
			(stroke
				(width 0.1524)
				(type default)
			)
			(layer "B.SilkS")
		)
		(fp_line
			(start 1.1938 0.4064)
			(end 1.1938 -0.4064)
			(stroke
				(width 0.1)
				(type default)
			)
			(layer "B.Fab")
		)
		(fp_line
			(start 1.1938 -0.4064)
			(end 0.8636 -0.4064)
			(stroke
				(width 0.1)
				(type default)
			)
			(layer "B.Fab")
		)
		(fp_line
			(start 0.8636 0.4572)
			(end 0.8636 0.4064)
			(stroke
				(width 0.1)
				(type default)
			)
			(layer "B.Fab")
		)
		(fp_line
			(start 0.8636 0.4064)
			(end 1.1938 0.4064)
			(stroke
				(width 0.1)
				(type default)
			)
			(layer "B.Fab")
		)
		(fp_line
			(start 0.8636 -0.4064)
			(end 0.8636 -0.4572)
			(stroke
				(width 0.1)
				(type default)
			)
			(layer "B.Fab")
		)
		(fp_line
			(start 0.8636 -0.4572)
			(end -0.8636 -0.4572)
			(stroke
				(width 0.1)
				(type default)
			)
			(layer "B.Fab")
		)
		(fp_line
			(start -0.8636 0.4572)
			(end 0.8636 0.4572)
			(stroke
				(width 0.1)
				(type default)
			)
			(layer "B.Fab")
		)
		(fp_line
			(start -0.8636 0.4064)
			(end -0.8636 0.4572)
			(stroke
				(width 0.1)
				(type default)
			)
			(layer "B.Fab")
		)
		(fp_line
			(start -0.8636 -0.4064)
			(end -1.1938 -0.4064)
			(stroke
				(width 0.1)
				(type default)
			)
			(layer "B.Fab")
		)
		(fp_line
			(start -0.8636 -0.4572)
			(end -0.8636 -0.4064)
			(stroke
				(width 0.1)
				(type default)
			)
			(layer "B.Fab")
		)
		(fp_line
			(start -1.1938 0.4064)
			(end -0.8636 0.4064)
			(stroke
				(width 0.1)
				(type default)
			)
			(layer "B.Fab")
		)
		(fp_line
			(start -1.1938 -0.4064)
			(end -1.1938 0.4064)
			(stroke
				(width 0.1)
				(type default)
			)
			(layer "B.Fab")
		)
		(pad "1" smd rect
			(at 0.7366 0 90)
			(size 0.7112 0.8128)
			(layers "B.Cu" "B.Mask" "B.Paste")
			(net "P1V25_PEX3")
		)
		(pad "2" smd rect
			(at -0.7366 0 90)
			(size 0.7112 0.8128)
			(layers "B.Cu" "B.Mask" "B.Paste")
			(net "GND")
		)
	)
	(footprint ""
		(layer "B.Cu")
		(at 251.140722 -366.83696 180)
		(property "Reference" "PR6609"
			(at 0 0 0)
			(layer "B.SilkS")
			(hide yes)
			(effects
				(font
					(size 1.27 1.27)
				)
				(justify mirror)
			)
		)
		(property "Value" ""
			(at 0 0 0)
			(layer "B.Fab")
			(effects
				(font
					(size 1.27 1.27)
				)
				(justify mirror)
			)
		)
		(duplicate_pad_numbers_are_jumpers no)
		(fp_line
			(start 0.7874 0.4064)
			(end 0.7874 -0.4064)
			(stroke
				(width 0.1524)
				(type default)
			)
			(layer "B.SilkS")
		)
		(fp_line
			(start 0.7874 -0.4064)
			(end -0.7874 -0.4064)
			(stroke
				(width 0.1524)
				(type default)
			)
			(layer "B.SilkS")
		)
		(fp_line
			(start -0.7874 0.4064)
			(end 0.7874 0.4064)
			(stroke
				(width 0.1524)
				(type default)
			)
			(layer "B.SilkS")
		)
		(fp_line
			(start -0.7874 -0.4064)
			(end -0.7874 0.4064)
			(stroke
				(width 0.1524)
				(type default)
			)
			(layer "B.SilkS")
		)
		(fp_line
			(start 0.67945 0.3048)
			(end 0.67945 -0.305054)
			(stroke
				(width 0.1)
				(type default)
			)
			(layer "B.Fab")
		)
		(fp_line
			(start 0.67945 -0.305054)
			(end 0.12065 -0.305054)
			(stroke
				(width 0.1)
				(type default)
			)
			(layer "B.Fab")
		)
		(fp_line
			(start 0.12065 0.3048)
			(end 0.67945 0.3048)
			(stroke
				(width 0.1)
				(type default)
			)
			(layer "B.Fab")
		)
		(fp_line
			(start 0.12065 0.2794)
			(end 0.12065 0.3048)
			(stroke
				(width 0.1)
				(type default)
			)
			(layer "B.Fab")
		)
		(fp_line
			(start 0.12065 -0.2794)
			(end -0.12065 -0.2794)
			(stroke
				(width 0.1)
				(type default)
			)
			(layer "B.Fab")
		)
		(fp_line
			(start 0.12065 -0.305054)
			(end 0.12065 -0.2794)
			(stroke
				(width 0.1)
				(type default)
			)
			(layer "B.Fab")
		)
		(fp_line
			(start -0.120396 0.3048)
			(end -0.120396 0.2794)
			(stroke
				(width 0.1)
				(type default)
			)
			(layer "B.Fab")
		)
		(fp_line
			(start -0.120396 0.2794)
			(end 0.12065 0.2794)
			(stroke
				(width 0.1)
				(type default)
			)
			(layer "B.Fab")
		)
		(fp_line
			(start -0.12065 -0.2794)
			(end -0.12065 -0.3048)
			(stroke
				(width 0.1)
				(type default)
			)
			(layer "B.Fab")
		)
		(fp_line
			(start -0.12065 -0.3048)
			(end -0.67945 -0.3048)
			(stroke
				(width 0.1)
				(type default)
			)
			(layer "B.Fab")
		)
		(fp_line
			(start -0.67945 0.3048)
			(end -0.120396 0.3048)
			(stroke
				(width 0.1)
				(type default)
			)
			(layer "B.Fab")
		)
		(fp_line
			(start -0.67945 -0.3048)
			(end -0.67945 0.3048)
			(stroke
				(width 0.1)
				(type default)
			)
			(layer "B.Fab")
		)
		(pad "1" smd circle
			(at 0.40005 0)
			(size 0 0)
			(layers "B.Cu" "B.Mask" "B.Paste")
			(net "P12V_HSC_GATE2")
		)
		(pad "2" smd circle
			(at -0.40005 0)
			(size 0 0)
			(layers "B.Cu" "B.Mask" "B.Paste")
			(net "HS_GATE2_R_2")
		)
	)
	(footprint ""
		(layer "B.Cu")
		(at 171.949872 -292.099746 90)
		(property "Reference" "C1471"
			(at 0 0 90)
			(layer "B.SilkS")
			(hide yes)
			(effects
				(font
					(size 1.27 1.27)
				)
				(justify mirror)
			)
		)
		(property "Value" ""
			(at 0 0 90)
			(layer "B.Fab")
			(effects
				(font
					(size 1.27 1.27)
				)
				(justify mirror)
			)
		)
		(duplicate_pad_numbers_are_jumpers no)
		(fp_line
			(start 0.299974 -0.150114)
			(end -0.299974 -0.150114)
			(stroke
				(width 0.1)
				(type default)
			)
			(layer "B.Fab")
		)
		(fp_line
			(start -0.299974 -0.150114)
			(end -0.299974 0.150114)
			(stroke
				(width 0.1)
				(type default)
			)
			(layer "B.Fab")
		)
		(fp_line
			(start 0.299974 0.150114)
			(end 0.299974 -0.150114)
			(stroke
				(width 0.1)
				(type default)
			)
			(layer "B.Fab")
		)
		(fp_line
			(start -0.299974 0.150114)
			(end 0.299974 0.150114)
			(stroke
				(width 0.1)
				(type default)
			)
			(layer "B.Fab")
		)
		(pad "1" smd rect
			(at 0.2667 0 270)
			(size 0.3048 0.381)
			(layers "B.Cu" "B.Mask" "B.Paste")
			(net "P0V8_SERDES_VDDA_PEX1")
		)
		(pad "2" smd rect
			(at -0.2667 0 270)
			(size 0.3048 0.381)
			(layers "B.Cu" "B.Mask" "B.Paste")
			(net "GND")
		)
	)
	(footprint ""
		(layer "B.Cu")
		(at 217.235786 -221.350586)
		(property "Reference" "R1487"
			(at 0 0 0)
			(layer "B.SilkS")
			(hide yes)
			(effects
				(font
					(size 1.27 1.27)
				)
				(justify mirror)
			)
		)
		(property "Value" ""
			(at 0 0 0)
			(layer "B.Fab")
			(effects
				(font
					(size 1.27 1.27)
				)
				(justify mirror)
			)
		)
		(duplicate_pad_numbers_are_jumpers no)
		(fp_line
			(start -0.7874 -0.4064)
			(end -0.7874 0.4064)
			(stroke
				(width 0.1524)
				(type default)
			)
			(layer "B.SilkS")
		)
		(fp_line
			(start -0.7874 0.4064)
			(end 0.7874 0.4064)
			(stroke
				(width 0.1524)
				(type default)
			)
			(layer "B.SilkS")
		)
		(fp_line
			(start 0.7874 -0.4064)
			(end -0.7874 -0.4064)
			(stroke
				(width 0.1524)
				(type default)
			)
			(layer "B.SilkS")
		)
		(fp_line
			(start 0.7874 0.4064)
			(end 0.7874 -0.4064)
			(stroke
				(width 0.1524)
				(type default)
			)
			(layer "B.SilkS")
		)
		(fp_line
			(start -0.67945 -0.3048)
			(end -0.67945 0.3048)
			(stroke
				(width 0.1)
				(type default)
			)
			(layer "B.Fab")
		)
		(fp_line
			(start -0.67945 0.3048)
			(end -0.120396 0.3048)
			(stroke
				(width 0.1)
				(type default)
			)
			(layer "B.Fab")
		)
		(fp_line
			(start -0.12065 -0.3048)
			(end -0.67945 -0.3048)
			(stroke
				(width 0.1)
				(type default)
			)
			(layer "B.Fab")
		)
		(fp_line
			(start -0.12065 -0.2794)
			(end -0.12065 -0.3048)
			(stroke
				(width 0.1)
				(type default)
			)
			(layer "B.Fab")
		)
		(fp_line
			(start -0.120396 0.2794)
			(end 0.12065 0.2794)
			(stroke
				(width 0.1)
				(type default)
			)
			(layer "B.Fab")
		)
		(fp_line
			(start -0.120396 0.3048)
			(end -0.120396 0.2794)
			(stroke
				(width 0.1)
				(type default)
			)
			(layer "B.Fab")
		)
		(fp_line
			(start 0.12065 -0.305054)
			(end 0.12065 -0.2794)
			(stroke
				(width 0.1)
				(type default)
			)
			(layer "B.Fab")
		)
		(fp_line
			(start 0.12065 -0.2794)
			(end -0.12065 -0.2794)
			(stroke
				(width 0.1)
				(type default)
			)
			(layer "B.Fab")
		)
		(fp_line
			(start 0.12065 0.2794)
			(end 0.12065 0.3048)
			(stroke
				(width 0.1)
				(type default)
			)
			(layer "B.Fab")
		)
		(fp_line
			(start 0.12065 0.3048)
			(end 0.67945 0.3048)
			(stroke
				(width 0.1)
				(type default)
			)
			(layer "B.Fab")
		)
		(fp_line
			(start 0.67945 -0.305054)
			(end 0.12065 -0.305054)
			(stroke
				(width 0.1)
				(type default)
			)
			(layer "B.Fab")
		)
		(fp_line
			(start 0.67945 0.3048)
			(end 0.67945 -0.305054)
			(stroke
				(width 0.1)
				(type default)
			)
			(layer "B.Fab")
		)
		(pad "1" smd circle
			(at 0.40005 0 180)
			(size 0 0)
			(layers "B.Cu" "B.Mask" "B.Paste")
			(net "SMB_BIC_FPGA_SCL")
		)
		(pad "2" smd circle
			(at -0.40005 0 180)
			(size 0 0)
			(layers "B.Cu" "B.Mask" "B.Paste")
			(net "SMB_BIC_FPGA_R_SCL")
		)
	)
	(footprint ""
		(layer "B.Cu")
		(at 244.782086 -286.538162 180)
		(property "Reference" "PC252"
			(at 0 0 0)
			(layer "B.SilkS")
			(hide yes)
			(effects
				(font
					(size 1.27 1.27)
				)
				(justify mirror)
			)
		)
		(property "Value" ""
			(at 0 0 0)
			(layer "B.Fab")
			(effects
				(font
					(size 1.27 1.27)
				)
				(justify mirror)
			)
		)
		(duplicate_pad_numbers_are_jumpers no)
		(fp_line
			(start 1.524 0.762)
			(end 1.524 -0.762)
			(stroke
				(width 0.1524)
				(type default)
			)
			(layer "B.SilkS")
		)
		(fp_line
			(start 1.524 -0.762)
			(end -1.524 -0.762)
			(stroke
				(width 0.1524)
				(type default)
			)
			(layer "B.SilkS")
		)
		(fp_line
			(start -1.524 0.762)
			(end 1.524 0.762)
			(stroke
				(width 0.1524)
				(type default)
			)
			(layer "B.SilkS")
		)
		(fp_line
			(start -1.524 -0.762)
			(end -1.524 0.762)
			(stroke
				(width 0.1524)
				(type default)
			)
			(layer "B.SilkS")
		)
		(fp_line
			(start 1.1049 0.724916)
			(end -1.1049 0.724916)
			(stroke
				(width 0.1)
				(type default)
			)
			(layer "B.Fab")
		)
		(fp_line
			(start 1.1049 -0.724916)
			(end 1.1049 0.724916)
			(stroke
				(width 0.1)
				(type default)
			)
			(layer "B.Fab")
		)
		(fp_line
			(start -1.1049 0.724916)
			(end -1.1049 -0.724916)
			(stroke
				(width 0.1)
				(type default)
			)
			(layer "B.Fab")
		)
		(fp_line
			(start -1.1049 -0.724916)
			(end 1.1049 -0.724916)
			(stroke
				(width 0.1)
				(type default)
			)
			(layer "B.Fab")
		)
		(pad "1" smd rect
			(at 0.889 0 180)
			(size 1.016 1.27)
			(layers "B.Cu" "B.Mask" "B.Paste")
			(net "P1V25_PEX2_R")
		)
		(pad "2" smd rect
			(at -0.889 0 180)
			(size 1.016 1.27)
			(layers "B.Cu" "B.Mask" "B.Paste")
			(net "GND")
		)
	)
	(footprint ""
		(layer "B.Cu")
		(at 134.808214 -213.524846 180)
		(property "Reference" "R994"
			(at 0 0 0)
			(layer "B.SilkS")
			(hide yes)
			(effects
				(font
					(size 1.27 1.27)
				)
				(justify mirror)
			)
		)
		(property "Value" ""
			(at 0 0 0)
			(layer "B.Fab")
			(effects
				(font
					(size 1.27 1.27)
				)
				(justify mirror)
			)
		)
		(duplicate_pad_numbers_are_jumpers no)
		(fp_line
			(start 0.7874 0.4064)
			(end 0.7874 -0.4064)
			(stroke
				(width 0.1524)
				(type default)
			)
			(layer "B.SilkS")
		)
		(fp_line
			(start 0.7874 -0.4064)
			(end -0.7874 -0.4064)
			(stroke
				(width 0.1524)
				(type default)
			)
			(layer "B.SilkS")
		)
		(fp_line
			(start -0.7874 0.4064)
			(end 0.7874 0.4064)
			(stroke
				(width 0.1524)
				(type default)
			)
			(layer "B.SilkS")
		)
		(fp_line
			(start -0.7874 -0.4064)
			(end -0.7874 0.4064)
			(stroke
				(width 0.1524)
				(type default)
			)
			(layer "B.SilkS")
		)
		(fp_line
			(start 0.67945 0.3048)
			(end 0.67945 -0.305054)
			(stroke
				(width 0.1)
				(type default)
			)
			(layer "B.Fab")
		)
		(fp_line
			(start 0.67945 -0.305054)
			(end 0.12065 -0.305054)
			(stroke
				(width 0.1)
				(type default)
			)
			(layer "B.Fab")
		)
		(fp_line
			(start 0.12065 0.3048)
			(end 0.67945 0.3048)
			(stroke
				(width 0.1)
				(type default)
			)
			(layer "B.Fab")
		)
		(fp_line
			(start 0.12065 0.2794)
			(end 0.12065 0.3048)
			(stroke
				(width 0.1)
				(type default)
			)
			(layer "B.Fab")
		)
		(fp_line
			(start 0.12065 -0.2794)
			(end -0.12065 -0.2794)
			(stroke
				(width 0.1)
				(type default)
			)
			(layer "B.Fab")
		)
		(fp_line
			(start 0.12065 -0.305054)
			(end 0.12065 -0.2794)
			(stroke
				(width 0.1)
				(type default)
			)
			(layer "B.Fab")
		)
		(fp_line
			(start -0.120396 0.3048)
			(end -0.120396 0.2794)
			(stroke
				(width 0.1)
				(type default)
			)
			(layer "B.Fab")
		)
		(fp_line
			(start -0.120396 0.2794)
			(end 0.12065 0.2794)
			(stroke
				(width 0.1)
				(type default)
			)
			(layer "B.Fab")
		)
		(fp_line
			(start -0.12065 -0.2794)
			(end -0.12065 -0.3048)
			(stroke
				(width 0.1)
				(type default)
			)
			(layer "B.Fab")
		)
		(fp_line
			(start -0.12065 -0.3048)
			(end -0.67945 -0.3048)
			(stroke
				(width 0.1)
				(type default)
			)
			(layer "B.Fab")
		)
		(fp_line
			(start -0.67945 0.3048)
			(end -0.120396 0.3048)
			(stroke
				(width 0.1)
				(type default)
			)
			(layer "B.Fab")
		)
		(fp_line
			(start -0.67945 -0.3048)
			(end -0.67945 0.3048)
			(stroke
				(width 0.1)
				(type default)
			)
			(layer "B.Fab")
		)
		(pad "1" smd circle
			(at 0.40005 0)
			(size 0 0)
			(layers "B.Cu" "B.Mask" "B.Paste")
			(net "UART_PEX2_CLI_BUF_TX")
		)
		(pad "2" smd circle
			(at -0.40005 0)
			(size 0 0)
			(layers "B.Cu" "B.Mask" "B.Paste")
			(net "P3V3_AUX")
		)
	)
	(footprint ""
		(layer "B.Cu")
		(at 272.373598 -296.9514 180)
		(property "Reference" "R3474"
			(at 0 0 0)
			(layer "B.SilkS")
			(hide yes)
			(effects
				(font
					(size 1.27 1.27)
				)
				(justify mirror)
			)
		)
		(property "Value" ""
			(at 0 0 0)
			(layer "B.Fab")
			(effects
				(font
					(size 1.27 1.27)
				)
				(justify mirror)
			)
		)
		(duplicate_pad_numbers_are_jumpers no)
		(fp_line
			(start 0.7874 0.4064)
			(end 0.7874 -0.4064)
			(stroke
				(width 0.1524)
				(type default)
			)
			(layer "B.SilkS")
		)
		(fp_line
			(start 0.7874 -0.4064)
			(end -0.7874 -0.4064)
			(stroke
				(width 0.1524)
				(type default)
			)
			(layer "B.SilkS")
		)
		(fp_line
			(start -0.7874 0.4064)
			(end 0.7874 0.4064)
			(stroke
				(width 0.1524)
				(type default)
			)
			(layer "B.SilkS")
		)
		(fp_line
			(start -0.7874 -0.4064)
			(end -0.7874 0.4064)
			(stroke
				(width 0.1524)
				(type default)
			)
			(layer "B.SilkS")
		)
		(fp_line
			(start 0.67945 0.3048)
			(end 0.67945 -0.305054)
			(stroke
				(width 0.1)
				(type default)
			)
			(layer "B.Fab")
		)
		(fp_line
			(start 0.67945 -0.305054)
			(end 0.12065 -0.305054)
			(stroke
				(width 0.1)
				(type default)
			)
			(layer "B.Fab")
		)
		(fp_line
			(start 0.12065 0.3048)
			(end 0.67945 0.3048)
			(stroke
				(width 0.1)
				(type default)
			)
			(layer "B.Fab")
		)
		(fp_line
			(start 0.12065 0.2794)
			(end 0.12065 0.3048)
			(stroke
				(width 0.1)
				(type default)
			)
			(layer "B.Fab")
		)
		(fp_line
			(start 0.12065 -0.2794)
			(end -0.12065 -0.2794)
			(stroke
				(width 0.1)
				(type default)
			)
			(layer "B.Fab")
		)
		(fp_line
			(start 0.12065 -0.305054)
			(end 0.12065 -0.2794)
			(stroke
				(width 0.1)
				(type default)
			)
			(layer "B.Fab")
		)
		(fp_line
			(start -0.120396 0.3048)
			(end -0.120396 0.2794)
			(stroke
				(width 0.1)
				(type default)
			)
			(layer "B.Fab")
		)
		(fp_line
			(start -0.120396 0.2794)
			(end 0.12065 0.2794)
			(stroke
				(width 0.1)
				(type default)
			)
			(layer "B.Fab")
		)
		(fp_line
			(start -0.12065 -0.2794)
			(end -0.12065 -0.3048)
			(stroke
				(width 0.1)
				(type default)
			)
			(layer "B.Fab")
		)
		(fp_line
			(start -0.12065 -0.3048)
			(end -0.67945 -0.3048)
			(stroke
				(width 0.1)
				(type default)
			)
			(layer "B.Fab")
		)
		(fp_line
			(start -0.67945 0.3048)
			(end -0.120396 0.3048)
			(stroke
				(width 0.1)
				(type default)
			)
			(layer "B.Fab")
		)
		(fp_line
			(start -0.67945 -0.3048)
			(end -0.67945 0.3048)
			(stroke
				(width 0.1)
				(type default)
			)
			(layer "B.Fab")
		)
		(pad "1" smd circle
			(at 0.40005 0)
			(size 0 0)
			(layers "B.Cu" "B.Mask" "B.Paste")
			(net "SPI_PEX2_SDIO1_R")
		)
		(pad "2" smd circle
			(at -0.40005 0)
			(size 0 0)
			(layers "B.Cu" "B.Mask" "B.Paste")
			(net "SPI_PEX2_SDIO1")
		)
	)
)
